(kicad_pcb
	(version 20260206)
	(generator "pcbnew")
	(generator_version "10.0")
	(general
		(thickness 1.6)
		(legacy_teardrops no)
	)
	(paper "A4")
	(title_block
		(title "v1-chassis-manager — T6M_CM_d_v01_1031_1645.brd")
		(comment 1 "Open CloudServer (Microsoft) / footprints 130-139 of 2512")
	)
	(layers
		(0 "F.Cu" signal "TOP")
		(4 "In1.Cu" signal "GND1")
		(6 "In2.Cu" signal "IN1")
		(8 "In3.Cu" signal "VCC1")
		(10 "In4.Cu" signal "VCC2")
		(12 "In5.Cu" signal "GND2")
		(14 "In6.Cu" signal "IN2")
		(16 "In7.Cu" signal "IN3")
		(18 "In8.Cu" signal "GND3")
		(2 "B.Cu" signal "BOTTOM")
		(9 "F.Adhes" user "F.Adhesive")
		(11 "B.Adhes" user "B.Adhesive")
		(13 "F.Paste" user "Package Geometry/Pastemask Top")
		(15 "B.Paste" user "Package Geometry/Pastemask Bottom")
		(5 "F.SilkS" user "Ref Des/Silkscreen Top")
		(7 "B.SilkS" user "Ref Des/Silkscreen Bottom")
		(1 "F.Mask" user "Board Geometry/Soldermask Top")
		(3 "B.Mask" user "Board Geometry/Soldermask Bottom")
		(17 "Dwgs.User" user "User.Drawings")
		(19 "Cmts.User" user "User.Comments")
		(21 "Eco1.User" user "User.Eco1")
		(23 "Eco2.User" user "User.Eco2")
		(25 "Edge.Cuts" user "Board Geometry/Outline")
		(27 "Margin" user)
		(31 "F.CrtYd" user "Package Geometry/Place Bound Top")
		(29 "B.CrtYd" user "Package Geometry/Place Bound Bottom")
		(35 "F.Fab" user "Ref Des/Assembly Top")
		(33 "B.Fab" user "Ref Des/Assembly Bottom")
	)
	(footprint ""
		(layer "F.Cu")
		(at 127.593852 -155.853892)
		(property "Reference" "R1282"
			(at -62.858142 109.744256 0)
			(unlocked yes)
			(layer "F.SilkS")
			(effects
				(font
					(size 0.7874 0.5842)
					(thickness 0.1524)
				)
				(justify left)
			)
		)
		(property "Value" ""
			(at 0 0 0)
			(layer "F.Fab")
			(effects
				(font
					(size 1.27 1.27)
				)
			)
		)
		(duplicate_pad_numbers_are_jumpers no)
		(fp_line
			(start -0.7874 -0.4064)
			(end 0.7874 -0.4064)
			(stroke
				(width 0.1524)
				(type default)
			)
			(layer "F.SilkS")
		)
		(fp_line
			(start -0.7874 0.4064)
			(end -0.7874 -0.4064)
			(stroke
				(width 0.1524)
				(type default)
			)
			(layer "F.SilkS")
		)
		(fp_line
			(start 0.7874 -0.4064)
			(end 0.7874 0.4064)
			(stroke
				(width 0.1524)
				(type default)
			)
			(layer "F.SilkS")
		)
		(fp_line
			(start 0.7874 0.4064)
			(end -0.7874 0.4064)
			(stroke
				(width 0.1524)
				(type default)
			)
			(layer "F.SilkS")
		)
		(fp_poly
			(pts
				(xy -0.508 0.2794) (xy -0.508 0.2286) (xy -0.635 0.2286) (xy -0.635 -0.254) (xy -0.5334 -0.254)
				(xy -0.5334 -0.2794) (xy 0.5334 -0.2794) (xy 0.5334 -0.254) (xy 0.635 -0.254) (xy 0.635 0.254) (xy 0.5334 0.254)
				(xy 0.5334 0.2794)
			)
			(stroke
				(width 0)
				(type default)
			)
			(fill no)
			(layer "F.CrtYd")
		)
		(pad "1" smd rect
			(at 0.40005 0)
			(size 0.4572 0.508)
			(layers "F.Cu" "F.Mask" "F.Paste")
			(net "P5V_NODE1")
		)
		(pad "2" smd rect
			(at -0.40005 0)
			(size 0.4572 0.508)
			(layers "F.Cu" "F.Mask" "F.Paste")
			(net "PMBUS1_EN")
		)
	)
	(footprint ""
		(layer "F.Cu")
		(at 36.34359 -103.486712 180)
		(property "Reference" "C823"
			(at 0.802132 -3.263138 0)
			(unlocked yes)
			(layer "F.SilkS")
			(effects
				(font
					(size 0.7874 0.5842)
					(thickness 0.1524)
				)
				(justify left)
			)
		)
		(property "Value" ""
			(at 0 0 180)
			(layer "F.Fab")
			(effects
				(font
					(size 1.27 1.27)
				)
			)
		)
		(duplicate_pad_numbers_are_jumpers no)
		(fp_line
			(start 0.7874 0.4064)
			(end -0.7874 0.4064)
			(stroke
				(width 0.1524)
				(type default)
			)
			(layer "F.SilkS")
		)
		(fp_line
			(start 0.7874 -0.4064)
			(end 0.7874 0.4064)
			(stroke
				(width 0.1524)
				(type default)
			)
			(layer "F.SilkS")
		)
		(fp_line
			(start 0 0.381)
			(end 0 -0.381)
			(stroke
				(width 0.1524)
				(type default)
			)
			(layer "F.SilkS")
		)
		(fp_line
			(start -0.7874 0.4064)
			(end -0.7874 -0.4064)
			(stroke
				(width 0.1524)
				(type default)
			)
			(layer "F.SilkS")
		)
		(fp_line
			(start -0.7874 -0.4064)
			(end 0.7874 -0.4064)
			(stroke
				(width 0.1524)
				(type default)
			)
			(layer "F.SilkS")
		)
		(fp_poly
			(pts
				(xy -0.5334 0.254) (xy -0.635 0.254) (xy -0.635 0.2286) (xy -0.635 -0.254) (xy -0.5334 -0.254) (xy -0.5334 -0.2794)
				(xy 0.5334 -0.2794) (xy 0.5334 -0.254) (xy 0.635 -0.254) (xy 0.635 0.254) (xy 0.5334 0.254) (xy 0.5334 0.2794)
				(xy -0.508 0.2794) (xy -0.5334 0.2794)
			)
			(stroke
				(width 0)
				(type default)
			)
			(fill no)
			(layer "F.CrtYd")
		)
		(pad "1" smd rect
			(at 0.40005 0 180)
			(size 0.4572 0.508)
			(layers "F.Cu" "F.Mask" "F.Paste")
			(net "P1V5_SUS_NODE1_ADJ")
		)
		(pad "2" smd rect
			(at -0.40005 0 180)
			(size 0.4572 0.508)
			(layers "F.Cu" "F.Mask" "F.Paste")
			(net "P1V5_SUS_NODE1")
		)
	)
	(footprint ""
		(layer "F.Cu")
		(at 93.339158 -159.826452 90)
		(property "Reference" "R800"
			(at -71.245984 86.162642 0)
			(unlocked yes)
			(layer "F.SilkS")
			(effects
				(font
					(size 0.7874 0.5842)
					(thickness 0.1524)
				)
				(justify left)
			)
		)
		(property "Value" ""
			(at 0 0 90)
			(layer "F.Fab")
			(effects
				(font
					(size 1.27 1.27)
				)
			)
		)
		(duplicate_pad_numbers_are_jumpers no)
		(fp_line
			(start 0.7874 -0.4064)
			(end 0.7874 0.4064)
			(stroke
				(width 0.1524)
				(type default)
			)
			(layer "F.SilkS")
		)
		(fp_line
			(start -0.7874 -0.4064)
			(end 0.7874 -0.4064)
			(stroke
				(width 0.1524)
				(type default)
			)
			(layer "F.SilkS")
		)
		(fp_line
			(start 0.7874 0.4064)
			(end -0.7874 0.4064)
			(stroke
				(width 0.1524)
				(type default)
			)
			(layer "F.SilkS")
		)
		(fp_line
			(start -0.7874 0.4064)
			(end -0.7874 -0.4064)
			(stroke
				(width 0.1524)
				(type default)
			)
			(layer "F.SilkS")
		)
		(fp_poly
			(pts
				(xy -0.508 0.2794) (xy -0.508 0.2286) (xy -0.635 0.2286) (xy -0.635 -0.254) (xy -0.5334 -0.254)
				(xy -0.5334 -0.2794) (xy 0.5334 -0.2794) (xy 0.5334 -0.254) (xy 0.635 -0.254) (xy 0.635 0.254) (xy 0.5334 0.254)
				(xy 0.5334 0.2794)
			)
			(stroke
				(width 0)
				(type default)
			)
			(fill no)
			(layer "F.CrtYd")
		)
		(pad "1" smd rect
			(at 0.40005 0 90)
			(size 0.4572 0.508)
			(layers "F.Cu" "F.Mask" "F.Paste")
			(net "N52410998")
		)
		(pad "2" smd rect
			(at -0.40005 0 90)
			(size 0.4572 0.508)
			(layers "F.Cu" "F.Mask" "F.Paste")
			(net "P3V3_STB_NODE1")
		)
	)
	(footprint ""
		(layer "F.Cu")
		(at 111.87176 -171.609512 180)
		(property "Reference" "R664"
			(at 2.02438 10.435336 0)
			(unlocked yes)
			(layer "F.SilkS")
			(effects
				(font
					(size 0.7874 0.5842)
					(thickness 0.1524)
				)
				(justify left)
			)
		)
		(property "Value" ""
			(at 0 0 180)
			(layer "F.Fab")
			(effects
				(font
					(size 1.27 1.27)
				)
			)
		)
		(duplicate_pad_numbers_are_jumpers no)
		(fp_line
			(start 0.7874 0.4064)
			(end -0.7874 0.4064)
			(stroke
				(width 0.1524)
				(type default)
			)
			(layer "F.SilkS")
		)
		(fp_line
			(start 0.7874 -0.4064)
			(end 0.7874 0.4064)
			(stroke
				(width 0.1524)
				(type default)
			)
			(layer "F.SilkS")
		)
		(fp_line
			(start -0.7874 0.4064)
			(end -0.7874 -0.4064)
			(stroke
				(width 0.1524)
				(type default)
			)
			(layer "F.SilkS")
		)
		(fp_line
			(start -0.7874 -0.4064)
			(end 0.7874 -0.4064)
			(stroke
				(width 0.1524)
				(type default)
			)
			(layer "F.SilkS")
		)
		(fp_poly
			(pts
				(xy -0.508 0.2794) (xy -0.508 0.2286) (xy -0.635 0.2286) (xy -0.635 -0.254) (xy -0.5334 -0.254)
				(xy -0.5334 -0.2794) (xy 0.5334 -0.2794) (xy 0.5334 -0.254) (xy 0.635 -0.254) (xy 0.635 0.254) (xy 0.5334 0.254)
				(xy 0.5334 0.2794)
			)
			(stroke
				(width 0)
				(type default)
			)
			(fill no)
			(layer "F.CrtYd")
		)
		(pad "1" smd rect
			(at 0.40005 0 180)
			(size 0.4572 0.508)
			(layers "F.Cu" "F.Mask" "F.Paste")
			(net "P3V3_NODE1")
		)
		(pad "2" smd rect
			(at -0.40005 0 180)
			(size 0.4572 0.508)
			(layers "F.Cu" "F.Mask" "F.Paste")
			(net "I2C_COM3_SDA")
		)
	)
	(footprint ""
		(layer "F.Cu")
		(at 72.168512 -1.69418 180)
		(property "Reference" "C933"
			(at -1.024636 -1.075182 0)
			(unlocked yes)
			(layer "F.SilkS")
			(effects
				(font
					(size 0.7874 0.5842)
					(thickness 0.1524)
				)
				(justify left)
			)
		)
		(property "Value" ""
			(at 0 0 180)
			(layer "F.Fab")
			(effects
				(font
					(size 1.27 1.27)
				)
			)
		)
		(duplicate_pad_numbers_are_jumpers no)
		(fp_line
			(start 0.7874 0.4064)
			(end -0.7874 0.4064)
			(stroke
				(width 0.1524)
				(type default)
			)
			(layer "F.SilkS")
		)
		(fp_line
			(start 0.7874 -0.4064)
			(end 0.7874 0.4064)
			(stroke
				(width 0.1524)
				(type default)
			)
			(layer "F.SilkS")
		)
		(fp_line
			(start 0 0.381)
			(end 0 -0.381)
			(stroke
				(width 0.1524)
				(type default)
			)
			(layer "F.SilkS")
		)
		(fp_line
			(start -0.7874 0.4064)
			(end -0.7874 -0.4064)
			(stroke
				(width 0.1524)
				(type default)
			)
			(layer "F.SilkS")
		)
		(fp_line
			(start -0.7874 -0.4064)
			(end 0.7874 -0.4064)
			(stroke
				(width 0.1524)
				(type default)
			)
			(layer "F.SilkS")
		)
		(fp_poly
			(pts
				(xy -0.5334 0.254) (xy -0.635 0.254) (xy -0.635 0.2286) (xy -0.635 -0.254) (xy -0.5334 -0.254) (xy -0.5334 -0.2794)
				(xy 0.5334 -0.2794) (xy 0.5334 -0.254) (xy 0.635 -0.254) (xy 0.635 0.254) (xy 0.5334 0.254) (xy 0.5334 0.2794)
				(xy -0.508 0.2794) (xy -0.5334 0.2794)
			)
			(stroke
				(width 0)
				(type default)
			)
			(fill no)
			(layer "F.CrtYd")
		)
		(pad "1" smd rect
			(at 0.40005 0 180)
			(size 0.4572 0.508)
			(layers "F.Cu" "F.Mask" "F.Paste")
			(net "FM_CPLD_NODE1_P3V3_EN")
		)
		(pad "2" smd rect
			(at -0.40005 0 180)
			(size 0.4572 0.508)
			(layers "F.Cu" "F.Mask" "F.Paste")
			(net "GND")
		)
	)
	(footprint ""
		(layer "F.Cu")
		(at 62.817756 -14.910054 -90)
		(property "Reference" "PC81"
			(at 0.031242 8.700008 90)
			(unlocked yes)
			(layer "F.SilkS")
			(effects
				(font
					(size 0.7874 0.5842)
					(thickness 0.1524)
				)
				(justify left)
			)
		)
		(property "Value" ""
			(at 0 0 270)
			(layer "F.Fab")
			(effects
				(font
					(size 1.27 1.27)
				)
			)
		)
		(duplicate_pad_numbers_are_jumpers no)
		(fp_line
			(start -1.905 0.8636)
			(end -1.905 -0.8636)
			(stroke
				(width 0.1524)
				(type default)
			)
			(layer "F.SilkS")
		)
		(fp_line
			(start 1.905 0.8636)
			(end -1.905 0.8636)
			(stroke
				(width 0.1524)
				(type default)
			)
			(layer "F.SilkS")
		)
		(fp_line
			(start 0 0.8382)
			(end 0 -0.8382)
			(stroke
				(width 0.1524)
				(type default)
			)
			(layer "F.SilkS")
		)
		(fp_line
			(start -1.905 -0.8636)
			(end 1.905 -0.8636)
			(stroke
				(width 0.1524)
				(type default)
			)
			(layer "F.SilkS")
		)
		(fp_line
			(start 1.905 -0.8636)
			(end 1.905 0.8636)
			(stroke
				(width 0.1524)
				(type default)
			)
			(layer "F.SilkS")
		)
		(fp_rect
			(start -1.524 0.7366)
			(end 1.524 -0.7366)
			(stroke
				(width 0)
				(type default)
			)
			(fill no)
			(layer "F.CrtYd")
		)
		(pad "1" smd rect
			(at 0.94996 0 270)
			(size 1.1176 1.3716)
			(layers "F.Cu" "F.Mask" "F.Paste")
			(net "PV_VDDR_NODE1")
		)
		(pad "2" smd rect
			(at -0.94996 0 270)
			(size 1.1176 1.3716)
			(layers "F.Cu" "F.Mask" "F.Paste")
			(net "GND")
		)
	)
	(footprint ""
		(layer "F.Cu")
		(at 33.169606 -106.210608 180)
		(property "Reference" "C824"
			(at -1.516126 -0.667766 0)
			(unlocked yes)
			(layer "F.SilkS")
			(effects
				(font
					(size 0.7874 0.5842)
					(thickness 0.1524)
				)
				(justify left)
			)
		)
		(property "Value" ""
			(at 0 0 180)
			(layer "F.Fab")
			(effects
				(font
					(size 1.27 1.27)
				)
			)
		)
		(duplicate_pad_numbers_are_jumpers no)
		(fp_line
			(start 0.7874 0.4064)
			(end -0.7874 0.4064)
			(stroke
				(width 0.1524)
				(type default)
			)
			(layer "F.SilkS")
		)
		(fp_line
			(start 0.7874 -0.4064)
			(end 0.7874 0.4064)
			(stroke
				(width 0.1524)
				(type default)
			)
			(layer "F.SilkS")
		)
		(fp_line
			(start 0 0.381)
			(end 0 -0.381)
			(stroke
				(width 0.1524)
				(type default)
			)
			(layer "F.SilkS")
		)
		(fp_line
			(start -0.7874 0.4064)
			(end -0.7874 -0.4064)
			(stroke
				(width 0.1524)
				(type default)
			)
			(layer "F.SilkS")
		)
		(fp_line
			(start -0.7874 -0.4064)
			(end 0.7874 -0.4064)
			(stroke
				(width 0.1524)
				(type default)
			)
			(layer "F.SilkS")
		)
		(fp_poly
			(pts
				(xy -0.5334 0.254) (xy -0.635 0.254) (xy -0.635 0.2286) (xy -0.635 -0.254) (xy -0.5334 -0.254) (xy -0.5334 -0.2794)
				(xy 0.5334 -0.2794) (xy 0.5334 -0.254) (xy 0.635 -0.254) (xy 0.635 0.254) (xy 0.5334 0.254) (xy 0.5334 0.2794)
				(xy -0.508 0.2794) (xy -0.5334 0.2794)
			)
			(stroke
				(width 0)
				(type default)
			)
			(fill no)
			(layer "F.CrtYd")
		)
		(pad "1" smd rect
			(at 0.40005 0 180)
			(size 0.4572 0.508)
			(layers "F.Cu" "F.Mask" "F.Paste")
			(net "GND")
		)
		(pad "2" smd rect
			(at -0.40005 0 180)
			(size 0.4572 0.508)
			(layers "F.Cu" "F.Mask" "F.Paste")
			(net "PWRGD_NODE1_P1V5_SUS_PG")
		)
	)
	(footprint ""
		(layer "F.Cu")
		(at 38.348412 -19.015202 180)
		(property "Reference" "R212"
			(at -1.984248 -0.002794 0)
			(unlocked yes)
			(layer "F.SilkS")
			(effects
				(font
					(size 0.7874 0.5842)
					(thickness 0.1524)
				)
				(justify left)
			)
		)
		(property "Value" ""
			(at 0 0 180)
			(layer "F.Fab")
			(effects
				(font
					(size 1.27 1.27)
				)
			)
		)
		(duplicate_pad_numbers_are_jumpers no)
		(fp_line
			(start 0.7874 0.4064)
			(end -0.7874 0.4064)
			(stroke
				(width 0.1524)
				(type default)
			)
			(layer "F.SilkS")
		)
		(fp_line
			(start 0.7874 -0.4064)
			(end 0.7874 0.4064)
			(stroke
				(width 0.1524)
				(type default)
			)
			(layer "F.SilkS")
		)
		(fp_line
			(start -0.7874 0.4064)
			(end -0.7874 -0.4064)
			(stroke
				(width 0.1524)
				(type default)
			)
			(layer "F.SilkS")
		)
		(fp_line
			(start -0.7874 -0.4064)
			(end 0.7874 -0.4064)
			(stroke
				(width 0.1524)
				(type default)
			)
			(layer "F.SilkS")
		)
		(fp_poly
			(pts
				(xy -0.508 0.2794) (xy -0.508 0.2286) (xy -0.635 0.2286) (xy -0.635 -0.254) (xy -0.5334 -0.254)
				(xy -0.5334 -0.2794) (xy 0.5334 -0.2794) (xy 0.5334 -0.254) (xy 0.635 -0.254) (xy 0.635 0.254) (xy 0.5334 0.254)
				(xy 0.5334 0.2794)
			)
			(stroke
				(width 0)
				(type default)
			)
			(fill no)
			(layer "F.CrtYd")
		)
		(pad "1" smd rect
			(at 0.40005 0 180)
			(size 0.4572 0.508)
			(layers "F.Cu" "F.Mask" "F.Paste")
			(net "GND")
		)
		(pad "2" smd rect
			(at -0.40005 0 180)
			(size 0.4572 0.508)
			(layers "F.Cu" "F.Mask" "F.Paste")
			(net "PD_NODE1_DM0")
		)
	)
	(footprint ""
		(layer "F.Cu")
		(at 51.310286 -117.869462 -90)
		(property "Reference" "R311"
			(at -0.18034 7.234428 0)
			(unlocked yes)
			(layer "F.SilkS")
			(effects
				(font
					(size 0.7874 0.5842)
					(thickness 0.1524)
				)
				(justify left)
			)
		)
		(property "Value" ""
			(at 0 0 270)
			(layer "F.Fab")
			(effects
				(font
					(size 1.27 1.27)
				)
			)
		)
		(duplicate_pad_numbers_are_jumpers no)
		(fp_line
			(start -0.7874 0.4064)
			(end -0.7874 -0.4064)
			(stroke
				(width 0.1524)
				(type default)
			)
			(layer "F.SilkS")
		)
		(fp_line
			(start 0.7874 0.4064)
			(end -0.7874 0.4064)
			(stroke
				(width 0.1524)
				(type default)
			)
			(layer "F.SilkS")
		)
		(fp_line
			(start -0.7874 -0.4064)
			(end 0.7874 -0.4064)
			(stroke
				(width 0.1524)
				(type default)
			)
			(layer "F.SilkS")
		)
		(fp_line
			(start 0.7874 -0.4064)
			(end 0.7874 0.4064)
			(stroke
				(width 0.1524)
				(type default)
			)
			(layer "F.SilkS")
		)
		(fp_poly
			(pts
				(xy -0.508 0.2794) (xy -0.508 0.2286) (xy -0.635 0.2286) (xy -0.635 -0.254) (xy -0.5334 -0.254)
				(xy -0.5334 -0.2794) (xy 0.5334 -0.2794) (xy 0.5334 -0.254) (xy 0.635 -0.254) (xy 0.635 0.254) (xy 0.5334 0.254)
				(xy 0.5334 0.2794)
			)
			(stroke
				(width 0)
				(type default)
			)
			(fill no)
			(layer "F.CrtYd")
		)
		(pad "1" smd rect
			(at 0.40005 0 270)
			(size 0.4572 0.508)
			(layers "F.Cu" "F.Mask" "F.Paste")
			(net "BMC_NODE1_OSC1_EN")
		)
		(pad "2" smd rect
			(at -0.40005 0 270)
			(size 0.4572 0.508)
			(layers "F.Cu" "F.Mask" "F.Paste")
			(net "BMC_NODE1_OSC1_VDD")
		)
	)
	(footprint ""
		(layer "F.Cu")
		(at 19.195542 -128.414526 90)
		(property "Reference" "PC60"
			(at -2.1082 5.06476 90)
			(unlocked yes)
			(layer "F.SilkS")
			(effects
				(font
					(size 0.7874 0.5842)
					(thickness 0.1524)
				)
				(justify left)
			)
		)
		(property "Value" ""
			(at 0 0 90)
			(layer "F.Fab")
			(effects
				(font
					(size 1.27 1.27)
				)
			)
		)
		(duplicate_pad_numbers_are_jumpers no)
		(fp_line
			(start 0.7874 -0.4064)
			(end 0.7874 0.4064)
			(stroke
				(width 0.1524)
				(type default)
			)
			(layer "F.SilkS")
		)
		(fp_line
			(start -0.7874 -0.4064)
			(end 0.7874 -0.4064)
			(stroke
				(width 0.1524)
				(type default)
			)
			(layer "F.SilkS")
		)
		(fp_line
			(start 0 0.381)
			(end 0 -0.381)
			(stroke
				(width 0.1524)
				(type default)
			)
			(layer "F.SilkS")
		)
		(fp_line
			(start 0.7874 0.4064)
			(end -0.7874 0.4064)
			(stroke
				(width 0.1524)
				(type default)
			)
			(layer "F.SilkS")
		)
		(fp_line
			(start -0.7874 0.4064)
			(end -0.7874 -0.4064)
			(stroke
				(width 0.1524)
				(type default)
			)
			(layer "F.SilkS")
		)
		(fp_poly
			(pts
				(xy -0.5334 0.254) (xy -0.635 0.254) (xy -0.635 0.2286) (xy -0.635 -0.254) (xy -0.5334 -0.254) (xy -0.5334 -0.2794)
				(xy 0.5334 -0.2794) (xy 0.5334 -0.254) (xy 0.635 -0.254) (xy 0.635 0.254) (xy 0.5334 0.254) (xy 0.5334 0.2794)
				(xy -0.508 0.2794) (xy -0.5334 0.2794)
			)
			(stroke
				(width 0)
				(type default)
			)
			(fill no)
			(layer "F.CrtYd")
		)
		(pad "1" smd rect
			(at 0.40005 0 90)
			(size 0.4572 0.508)
			(layers "F.Cu" "F.Mask" "F.Paste")
			(net "SW_P1V05_NODE1_BT")
		)
		(pad "2" smd rect
			(at -0.40005 0 90)
			(size 0.4572 0.508)
			(layers "F.Cu" "F.Mask" "F.Paste")
			(net "SW_P1V05_NODE1_PH")
		)
	)
)
